(kicad_pcb
	(version 20260206)
	(generator "pcbnew")
	(generator_version "10.0")
	(general
		(thickness 1.6)
		(legacy_teardrops no)
	)
	(paper "A4")
	(title_block
		(title "panther-plus-userver — 13130-1b_20150205.brd")
		(comment 1 "Honey Badger (Wiwynn) / footprint 624 of 1509 (DIMM4), pads 128-134 of 210")
	)
	(layers
		(0 "F.Cu" signal "TOP")
		(4 "In1.Cu" signal "L2")
		(6 "In2.Cu" signal "L3")
		(8 "In3.Cu" signal "L4")
		(10 "In4.Cu" signal "L5")
		(12 "In5.Cu" signal "L6")
		(14 "In6.Cu" signal "L7")
		(16 "In7.Cu" signal "L8")
		(18 "In8.Cu" signal "L9")
		(20 "In9.Cu" signal "L10")
		(22 "In10.Cu" signal "L11")
		(2 "B.Cu" signal "BOTTOM")
		(9 "F.Adhes" user "F.Adhesive")
		(11 "B.Adhes" user "B.Adhesive")
		(13 "F.Paste" user "Package Geometry/Pastemask Top")
		(15 "B.Paste" user "Package Geometry/Pastemask Bottom")
		(5 "F.SilkS" user "Ref Des/Silkscreen Top")
		(7 "B.SilkS" user "Ref Des/Silkscreen Bottom")
		(1 "F.Mask" user "Board Geometry/Soldermask Top")
		(3 "B.Mask" user "Board Geometry/Soldermask Bottom")
		(17 "Dwgs.User" user "User.Drawings")
		(19 "Cmts.User" user "User.Comments")
		(21 "Eco1.User" user "User.Eco1")
		(23 "Eco2.User" user "User.Eco2")
		(25 "Edge.Cuts" user "Board Geometry/Outline")
		(27 "Margin" user)
		(31 "F.CrtYd" user "Package Geometry/Place Bound Top")
		(29 "B.CrtYd" user "Package Geometry/Place Bound Bottom")
		(35 "F.Fab" user "Ref Des/Assembly Top")
		(33 "B.Fab" user "Ref Des/Assembly Bottom")
	)
	(footprint ""
		(layer "F.Cu")
		(at 159.999934 -5.790692)
		(property "Reference" "DIMM4"
			(at 0 0 0)
			(layer "F.SilkS")
			(hide yes)
			(effects
				(font
					(size 1.27 1.27)
				)
			)
		)
		(property "Value" "DDR3-204P-174-COLAY-1-GP"
			(at -40.682164 -17.468088 0)
			(unlocked yes)
			(layer "F.Fab")
			(hide yes)
			(effects
				(font
					(size 1.016 1.016)
					(thickness 0.1524)
				)
			)
		)
		(property "Device Type" "AS0A626-H8SN-7H-COLAY-1"
			(at -40.682164 -18.992088 0)
			(unlocked yes)
			(layer "F.Fab")
			(hide yes)
			(effects
				(font
					(size 1.016 1.016)
					(thickness 0.1524)
				)
			)
		)
		(duplicate_pad_numbers_are_jumpers no)
		(pad "126" smd custom
			(at 8.24992 -4.106672)
			(size 0.1143 0.1143)
			(layers "F.Cu" "F.Mask" "F.Paste")
			(net "M_B_ODT2")
			(options
				(clearance outline)
				(anchor circle)
			)
			(primitives
				(gr_poly
					(pts
						(xy 0 0.9017) (xy -0.03175 0.89916) (xy -0.0635 0.889) (xy -0.09144 0.87376) (xy -0.11684 0.85344)
						(xy -0.13716 0.82804) (xy -0.1524 0.8001) (xy -0.16256 0.76835) (xy -0.1651 0.7366) (xy -0.1651 0.44958)
						(xy -0.17272 0.44196) (xy -0.19812 0.4064) (xy -0.2032 0.39624) (xy -0.20701 0.38735) (xy -0.21209 0.37719)
						(xy -0.2159 0.36703) (xy -0.21844 0.35687) (xy -0.22225 0.34544) (xy -0.22352 0.33528) (xy -0.22606 0.32512)
						(xy -0.22733 0.31369) (xy -0.22733 0.30353) (xy -0.2286 0.2921) (xy -0.22733 0.28067) (xy -0.22733 0.27051)
						(xy -0.22606 0.25908) (xy -0.22352 0.24892) (xy -0.22225 0.23876) (xy -0.21844 0.22733) (xy -0.2159 0.21717)
						(xy -0.21209 0.20701) (xy -0.20701 0.19685) (xy -0.2032 0.18796) (xy -0.19812 0.1778) (xy -0.17272 0.14224)
						(xy -0.1651 0.13462) (xy -0.1651 -0.7366) (xy -0.16256 -0.76835) (xy -0.1524 -0.8001) (xy -0.13716 -0.82804)
						(xy -0.11684 -0.85344) (xy -0.09144 -0.87376) (xy -0.0635 -0.889) (xy -0.03175 -0.89916) (xy 0 -0.9017)
						(xy 0.03175 -0.89916) (xy 0.0635 -0.889) (xy 0.09144 -0.87376) (xy 0.11684 -0.85344) (xy 0.13716 -0.82804)
						(xy 0.1524 -0.8001) (xy 0.16256 -0.76835) (xy 0.1651 -0.7366) (xy 0.1651 0.13462) (xy 0.17272 0.14224)
						(xy 0.19812 0.1778) (xy 0.2032 0.18796) (xy 0.20701 0.19685) (xy 0.21209 0.20701) (xy 0.2159 0.21717)
						(xy 0.21844 0.22733) (xy 0.22225 0.23876) (xy 0.22352 0.24892) (xy 0.22606 0.25908) (xy 0.22733 0.27051)
						(xy 0.22733 0.28067) (xy 0.2286 0.2921) (xy 0.22733 0.30353) (xy 0.22733 0.31369) (xy 0.22606 0.32512)
						(xy 0.22352 0.33528) (xy 0.22225 0.34544) (xy 0.21844 0.35687) (xy 0.2159 0.36703) (xy 0.21209 0.37719)
						(xy 0.20701 0.38735) (xy 0.2032 0.39624) (xy 0.19812 0.4064) (xy 0.17272 0.44196) (xy 0.1651 0.44958)
						(xy 0.1651 0.7366) (xy 0.16256 0.76835) (xy 0.1524 0.8001) (xy 0.13716 0.82804) (xy 0.11684 0.85344)
						(xy 0.09144 0.87376) (xy 0.0635 0.889) (xy 0.03175 0.89916)
					)
					(width 0)
					(fill yes)
				)
			)
		)
		(pad "127" smd custom
			(at 8.549894 4.106672)
			(size 0.1143 0.1143)
			(layers "F.Cu" "F.Mask" "F.Paste")
			(net "M_B_CS_N2")
			(options
				(clearance outline)
				(anchor circle)
			)
			(primitives
				(gr_poly
					(pts
						(xy 0 0.9017) (xy -0.03175 0.89916) (xy -0.0635 0.889) (xy -0.09144 0.87376) (xy -0.11684 0.85344)
						(xy -0.13716 0.82804) (xy -0.1524 0.8001) (xy -0.16256 0.76835) (xy -0.1651 0.7366) (xy -0.1651 0.11938)
						(xy -0.17272 0.11176) (xy -0.19812 0.0762) (xy -0.2032 0.06604) (xy -0.20701 0.05715) (xy -0.21209 0.04699)
						(xy -0.2159 0.03683) (xy -0.21844 0.02667) (xy -0.22225 0.01524) (xy -0.22352 0.00508) (xy -0.22606 -0.00508)
						(xy -0.22733 -0.01651) (xy -0.22733 -0.02667) (xy -0.2286 -0.0381) (xy -0.22733 -0.04953) (xy -0.22733 -0.05969)
						(xy -0.22606 -0.07112) (xy -0.22352 -0.08128) (xy -0.22225 -0.09144) (xy -0.21844 -0.10287) (xy -0.2159 -0.11303)
						(xy -0.21209 -0.12319) (xy -0.20701 -0.13335) (xy -0.2032 -0.14224) (xy -0.19812 -0.1524) (xy -0.17272 -0.18796)
						(xy -0.1651 -0.19558) (xy -0.1651 -0.7366) (xy -0.16256 -0.76835) (xy -0.1524 -0.8001) (xy -0.13716 -0.82804)
						(xy -0.11684 -0.85344) (xy -0.09144 -0.87376) (xy -0.0635 -0.889) (xy -0.03175 -0.89916) (xy 0 -0.9017)
						(xy 0.03175 -0.89916) (xy 0.0635 -0.889) (xy 0.09144 -0.87376) (xy 0.11684 -0.85344) (xy 0.13716 -0.82804)
						(xy 0.1524 -0.8001) (xy 0.16256 -0.76835) (xy 0.1651 -0.7366) (xy 0.1651 -0.19685) (xy 0.17272 -0.18923)
						(xy 0.17907 -0.18034) (xy 0.18669 -0.17145) (xy 0.19177 -0.16256) (xy 0.19812 -0.15367) (xy 0.20828 -0.13335)
						(xy 0.21971 -0.10287) (xy 0.22225 -0.09271) (xy 0.22479 -0.08128) (xy 0.22606 -0.07112) (xy 0.2286 -0.05969)
						(xy 0.2286 -0.01651) (xy 0.22606 -0.00508) (xy 0.22479 0.00508) (xy 0.22225 0.01651) (xy 0.21971 0.02667)
						(xy 0.20828 0.05715) (xy 0.19812 0.07747) (xy 0.19177 0.08636) (xy 0.18669 0.09525) (xy 0.17907 0.10414)
						(xy 0.17272 0.11303) (xy 0.1651 0.12065) (xy 0.1651 0.7366) (xy 0.16256 0.76835) (xy 0.1524 0.8001)
						(xy 0.13716 0.82804) (xy 0.11684 0.85344) (xy 0.09144 0.87376) (xy 0.0635 0.889) (xy 0.03175 0.89916)
					)
					(width 0)
					(fill yes)
				)
			)
		)
		(pad "128" smd custom
			(at 8.850122 -4.106672)
			(size 0.1143 0.1143)
			(layers "F.Cu" "F.Mask" "F.Paste")
			(net "M_B_ODT3")
			(options
				(clearance outline)
				(anchor circle)
			)
			(primitives
				(gr_poly
					(pts
						(xy 0 0.9017) (xy -0.03175 0.89916) (xy -0.0635 0.889) (xy -0.09144 0.87376) (xy -0.11684 0.85344)
						(xy -0.13716 0.82804) (xy -0.1524 0.8001) (xy -0.16256 0.76835) (xy -0.1651 0.7366) (xy -0.1651 0.19685)
						(xy -0.17272 0.18923) (xy -0.17907 0.18034) (xy -0.18669 0.17145) (xy -0.19177 0.16256) (xy -0.19812 0.15367)
						(xy -0.20828 0.13335) (xy -0.21971 0.10287) (xy -0.22225 0.09271) (xy -0.22479 0.08128) (xy -0.22606 0.07112)
						(xy -0.2286 0.05969) (xy -0.2286 0.01651) (xy -0.22606 0.00508) (xy -0.22479 -0.00508) (xy -0.22225 -0.01651)
						(xy -0.21971 -0.02667) (xy -0.20828 -0.05715) (xy -0.19812 -0.07747) (xy -0.19177 -0.08636) (xy -0.18669 -0.09525)
						(xy -0.17907 -0.10414) (xy -0.17272 -0.11303) (xy -0.1651 -0.12065) (xy -0.1651 -0.7366) (xy -0.16256 -0.76835)
						(xy -0.1524 -0.8001) (xy -0.13716 -0.82804) (xy -0.11684 -0.85344) (xy -0.09144 -0.87376) (xy -0.0635 -0.889)
						(xy -0.03175 -0.89916) (xy 0 -0.9017) (xy 0.03175 -0.89916) (xy 0.0635 -0.889) (xy 0.09144 -0.87376)
						(xy 0.11684 -0.85344) (xy 0.13716 -0.82804) (xy 0.1524 -0.8001) (xy 0.16256 -0.76835) (xy 0.1651 -0.7366)
						(xy 0.1651 -0.11938) (xy 0.17272 -0.11176) (xy 0.19812 -0.0762) (xy 0.2032 -0.06604) (xy 0.20701 -0.05715)
						(xy 0.21209 -0.04699) (xy 0.2159 -0.03683) (xy 0.21844 -0.02667) (xy 0.22225 -0.01524) (xy 0.22352 -0.00508)
						(xy 0.22606 0.00508) (xy 0.22733 0.01651) (xy 0.22733 0.02667) (xy 0.2286 0.0381) (xy 0.22733 0.04953)
						(xy 0.22733 0.05969) (xy 0.22606 0.07112) (xy 0.22352 0.08128) (xy 0.22225 0.09144) (xy 0.21844 0.10287)
						(xy 0.2159 0.11303) (xy 0.21209 0.12319) (xy 0.20701 0.13335) (xy 0.2032 0.14224) (xy 0.19812 0.1524)
						(xy 0.17272 0.18796) (xy 0.1651 0.19558) (xy 0.1651 0.7366) (xy 0.16256 0.76835) (xy 0.1524 0.8001)
						(xy 0.13716 0.82804) (xy 0.11684 0.85344) (xy 0.09144 0.87376) (xy 0.0635 0.889) (xy 0.03175 0.89916)
					)
					(width 0)
					(fill yes)
				)
			)
		)
		(pad "129" smd custom
			(at 9.150096 4.106672)
			(size 0.1143 0.1143)
			(layers "F.Cu" "F.Mask" "F.Paste")
			(net "M_B_CS_N3")
			(options
				(clearance outline)
				(anchor circle)
			)
			(primitives
				(gr_poly
					(pts
						(xy 0 0.9017) (xy -0.03175 0.89916) (xy -0.0635 0.889) (xy -0.09144 0.87376) (xy -0.11684 0.85344)
						(xy -0.13716 0.82804) (xy -0.1524 0.8001) (xy -0.16256 0.76835) (xy -0.1651 0.7366) (xy -0.1651 -0.13462)
						(xy -0.17272 -0.14224) (xy -0.19812 -0.1778) (xy -0.2032 -0.18796) (xy -0.20701 -0.19685) (xy -0.21209 -0.20701)
						(xy -0.2159 -0.21717) (xy -0.21844 -0.22733) (xy -0.22225 -0.23876) (xy -0.22352 -0.24892) (xy -0.22606 -0.25908)
						(xy -0.22733 -0.27051) (xy -0.22733 -0.28067) (xy -0.2286 -0.2921) (xy -0.22733 -0.30353) (xy -0.22733 -0.31369)
						(xy -0.22606 -0.32512) (xy -0.22352 -0.33528) (xy -0.22225 -0.34544) (xy -0.21844 -0.35687) (xy -0.2159 -0.36703)
						(xy -0.21209 -0.37719) (xy -0.20701 -0.38735) (xy -0.2032 -0.39624) (xy -0.19812 -0.4064) (xy -0.17272 -0.44196)
						(xy -0.1651 -0.44958) (xy -0.1651 -0.7366) (xy -0.16256 -0.76835) (xy -0.1524 -0.8001) (xy -0.13716 -0.82804)
						(xy -0.11684 -0.85344) (xy -0.09144 -0.87376) (xy -0.0635 -0.889) (xy -0.03175 -0.89916) (xy 0 -0.9017)
						(xy 0.03175 -0.89916) (xy 0.0635 -0.889) (xy 0.09144 -0.87376) (xy 0.11684 -0.85344) (xy 0.13716 -0.82804)
						(xy 0.1524 -0.8001) (xy 0.16256 -0.76835) (xy 0.1651 -0.7366) (xy 0.1651 -0.44958) (xy 0.17272 -0.44196)
						(xy 0.19812 -0.4064) (xy 0.2032 -0.39624) (xy 0.20701 -0.38735) (xy 0.21209 -0.37719) (xy 0.2159 -0.36703)
						(xy 0.21844 -0.35687) (xy 0.22225 -0.34544) (xy 0.22352 -0.33528) (xy 0.22606 -0.32512) (xy 0.22733 -0.31369)
						(xy 0.22733 -0.30353) (xy 0.2286 -0.2921) (xy 0.22733 -0.28067) (xy 0.22733 -0.27051) (xy 0.22606 -0.25908)
						(xy 0.22352 -0.24892) (xy 0.22225 -0.23876) (xy 0.21844 -0.22733) (xy 0.2159 -0.21717) (xy 0.21209 -0.20701)
						(xy 0.20701 -0.19685) (xy 0.2032 -0.18796) (xy 0.19812 -0.1778) (xy 0.17272 -0.14224) (xy 0.1651 -0.13462)
						(xy 0.1651 0.7366) (xy 0.16256 0.76835) (xy 0.1524 0.8001) (xy 0.13716 0.82804) (xy 0.11684 0.85344)
						(xy 0.09144 0.87376) (xy 0.0635 0.889) (xy 0.03175 0.89916)
					)
					(width 0)
					(fill yes)
				)
			)
		)
		(pad "130" smd custom
			(at 9.45007 -4.106672)
			(size 0.1143 0.1143)
			(layers "F.Cu" "F.Mask" "F.Paste")
			(net "M_B_MA13")
			(options
				(clearance outline)
				(anchor circle)
			)
			(primitives
				(gr_poly
					(pts
						(xy 0 0.9017) (xy -0.03175 0.89916) (xy -0.0635 0.889) (xy -0.09144 0.87376) (xy -0.11684 0.85344)
						(xy -0.13716 0.82804) (xy -0.1524 0.8001) (xy -0.16256 0.76835) (xy -0.1651 0.7366) (xy -0.1651 0.44958)
						(xy -0.17272 0.44196) (xy -0.19812 0.4064) (xy -0.2032 0.39624) (xy -0.20701 0.38735) (xy -0.21209 0.37719)
						(xy -0.2159 0.36703) (xy -0.21844 0.35687) (xy -0.22225 0.34544) (xy -0.22352 0.33528) (xy -0.22606 0.32512)
						(xy -0.22733 0.31369) (xy -0.22733 0.30353) (xy -0.2286 0.2921) (xy -0.22733 0.28067) (xy -0.22733 0.27051)
						(xy -0.22606 0.25908) (xy -0.22352 0.24892) (xy -0.22225 0.23876) (xy -0.21844 0.22733) (xy -0.2159 0.21717)
						(xy -0.21209 0.20701) (xy -0.20701 0.19685) (xy -0.2032 0.18796) (xy -0.19812 0.1778) (xy -0.17272 0.14224)
						(xy -0.1651 0.13462) (xy -0.1651 -0.7366) (xy -0.16256 -0.76835) (xy -0.1524 -0.8001) (xy -0.13716 -0.82804)
						(xy -0.11684 -0.85344) (xy -0.09144 -0.87376) (xy -0.0635 -0.889) (xy -0.03175 -0.89916) (xy 0 -0.9017)
						(xy 0.03175 -0.89916) (xy 0.0635 -0.889) (xy 0.09144 -0.87376) (xy 0.11684 -0.85344) (xy 0.13716 -0.82804)
						(xy 0.1524 -0.8001) (xy 0.16256 -0.76835) (xy 0.1651 -0.7366) (xy 0.1651 0.13462) (xy 0.17272 0.14224)
						(xy 0.19812 0.1778) (xy 0.2032 0.18796) (xy 0.20701 0.19685) (xy 0.21209 0.20701) (xy 0.2159 0.21717)
						(xy 0.21844 0.22733) (xy 0.22225 0.23876) (xy 0.22352 0.24892) (xy 0.22606 0.25908) (xy 0.22733 0.27051)
						(xy 0.22733 0.28067) (xy 0.2286 0.2921) (xy 0.22733 0.30353) (xy 0.22733 0.31369) (xy 0.22606 0.32512)
						(xy 0.22352 0.33528) (xy 0.22225 0.34544) (xy 0.21844 0.35687) (xy 0.2159 0.36703) (xy 0.21209 0.37719)
						(xy 0.20701 0.38735) (xy 0.2032 0.39624) (xy 0.19812 0.4064) (xy 0.17272 0.44196) (xy 0.1651 0.44958)
						(xy 0.1651 0.7366) (xy 0.16256 0.76835) (xy 0.1524 0.8001) (xy 0.13716 0.82804) (xy 0.11684 0.85344)
						(xy 0.09144 0.87376) (xy 0.0635 0.889) (xy 0.03175 0.89916)
					)
					(width 0)
					(fill yes)
				)
			)
		)
		(pad "131" smd custom
			(at 9.750044 4.106672)
			(size 0.1143 0.1143)
			(layers "F.Cu" "F.Mask" "F.Paste")
			(net "PV_VDDR")
			(options
				(clearance outline)
				(anchor circle)
			)
			(primitives
				(gr_poly
					(pts
						(xy 0 0.9017) (xy -0.03175 0.89916) (xy -0.0635 0.889) (xy -0.09144 0.87376) (xy -0.11684 0.85344)
						(xy -0.13716 0.82804) (xy -0.1524 0.8001) (xy -0.16256 0.76835) (xy -0.1651 0.7366) (xy -0.1651 0.11938)
						(xy -0.17272 0.11176) (xy -0.19812 0.0762) (xy -0.2032 0.06604) (xy -0.20701 0.05715) (xy -0.21209 0.04699)
						(xy -0.2159 0.03683) (xy -0.21844 0.02667) (xy -0.22225 0.01524) (xy -0.22352 0.00508) (xy -0.22606 -0.00508)
						(xy -0.22733 -0.01651) (xy -0.22733 -0.02667) (xy -0.2286 -0.0381) (xy -0.22733 -0.04953) (xy -0.22733 -0.05969)
						(xy -0.22606 -0.07112) (xy -0.22352 -0.08128) (xy -0.22225 -0.09144) (xy -0.21844 -0.10287) (xy -0.2159 -0.11303)
						(xy -0.21209 -0.12319) (xy -0.20701 -0.13335) (xy -0.2032 -0.14224) (xy -0.19812 -0.1524) (xy -0.17272 -0.18796)
						(xy -0.1651 -0.19558) (xy -0.1651 -0.7366) (xy -0.16256 -0.76835) (xy -0.1524 -0.8001) (xy -0.13716 -0.82804)
						(xy -0.11684 -0.85344) (xy -0.09144 -0.87376) (xy -0.0635 -0.889) (xy -0.03175 -0.89916) (xy 0 -0.9017)
						(xy 0.03175 -0.89916) (xy 0.0635 -0.889) (xy 0.09144 -0.87376) (xy 0.11684 -0.85344) (xy 0.13716 -0.82804)
						(xy 0.1524 -0.8001) (xy 0.16256 -0.76835) (xy 0.1651 -0.7366) (xy 0.1651 -0.19685) (xy 0.17272 -0.18923)
						(xy 0.17907 -0.18034) (xy 0.18669 -0.17145) (xy 0.19177 -0.16256) (xy 0.19812 -0.15367) (xy 0.20828 -0.13335)
						(xy 0.21971 -0.10287) (xy 0.22225 -0.09271) (xy 0.22479 -0.08128) (xy 0.22606 -0.07112) (xy 0.2286 -0.05969)
						(xy 0.2286 -0.01651) (xy 0.22606 -0.00508) (xy 0.22479 0.00508) (xy 0.22225 0.01651) (xy 0.21971 0.02667)
						(xy 0.20828 0.05715) (xy 0.19812 0.07747) (xy 0.19177 0.08636) (xy 0.18669 0.09525) (xy 0.17907 0.10414)
						(xy 0.17272 0.11303) (xy 0.1651 0.12065) (xy 0.1651 0.7366) (xy 0.16256 0.76835) (xy 0.1524 0.8001)
						(xy 0.13716 0.82804) (xy 0.11684 0.85344) (xy 0.09144 0.87376) (xy 0.0635 0.889) (xy 0.03175 0.89916)
					)
					(width 0)
					(fill yes)
				)
			)
		)
		(pad "132" smd custom
			(at 10.050018 -4.106672)
			(size 0.1143 0.1143)
			(layers "F.Cu" "F.Mask" "F.Paste")
			(net "PV_VDDR")
			(options
				(clearance outline)
				(anchor circle)
			)
			(primitives
				(gr_poly
					(pts
						(xy 0 0.9017) (xy -0.03175 0.89916) (xy -0.0635 0.889) (xy -0.09144 0.87376) (xy -0.11684 0.85344)
						(xy -0.13716 0.82804) (xy -0.1524 0.8001) (xy -0.16256 0.76835) (xy -0.1651 0.7366) (xy -0.1651 0.19685)
						(xy -0.17272 0.18923) (xy -0.17907 0.18034) (xy -0.18669 0.17145) (xy -0.19177 0.16256) (xy -0.19812 0.15367)
						(xy -0.20828 0.13335) (xy -0.21971 0.10287) (xy -0.22225 0.09271) (xy -0.22479 0.08128) (xy -0.22606 0.07112)
						(xy -0.2286 0.05969) (xy -0.2286 0.01651) (xy -0.22606 0.00508) (xy -0.22479 -0.00508) (xy -0.22225 -0.01651)
						(xy -0.21971 -0.02667) (xy -0.20828 -0.05715) (xy -0.19812 -0.07747) (xy -0.19177 -0.08636) (xy -0.18669 -0.09525)
						(xy -0.17907 -0.10414) (xy -0.17272 -0.11303) (xy -0.1651 -0.12065) (xy -0.1651 -0.7366) (xy -0.16256 -0.76835)
						(xy -0.1524 -0.8001) (xy -0.13716 -0.82804) (xy -0.11684 -0.85344) (xy -0.09144 -0.87376) (xy -0.0635 -0.889)
						(xy -0.03175 -0.89916) (xy 0 -0.9017) (xy 0.03175 -0.89916) (xy 0.0635 -0.889) (xy 0.09144 -0.87376)
						(xy 0.11684 -0.85344) (xy 0.13716 -0.82804) (xy 0.1524 -0.8001) (xy 0.16256 -0.76835) (xy 0.1651 -0.7366)
						(xy 0.1651 -0.11938) (xy 0.17272 -0.11176) (xy 0.19812 -0.0762) (xy 0.2032 -0.06604) (xy 0.20701 -0.05715)
						(xy 0.21209 -0.04699) (xy 0.2159 -0.03683) (xy 0.21844 -0.02667) (xy 0.22225 -0.01524) (xy 0.22352 -0.00508)
						(xy 0.22606 0.00508) (xy 0.22733 0.01651) (xy 0.22733 0.02667) (xy 0.2286 0.0381) (xy 0.22733 0.04953)
						(xy 0.22733 0.05969) (xy 0.22606 0.07112) (xy 0.22352 0.08128) (xy 0.22225 0.09144) (xy 0.21844 0.10287)
						(xy 0.2159 0.11303) (xy 0.21209 0.12319) (xy 0.20701 0.13335) (xy 0.2032 0.14224) (xy 0.19812 0.1524)
						(xy 0.17272 0.18796) (xy 0.1651 0.19558) (xy 0.1651 0.7366) (xy 0.16256 0.76835) (xy 0.1524 0.8001)
						(xy 0.13716 0.82804) (xy 0.11684 0.85344) (xy 0.09144 0.87376) (xy 0.0635 0.889) (xy 0.03175 0.89916)
					)
					(width 0)
					(fill yes)
				)
			)
		)
	)
)
